FILE_TYPE = MACRO_DRAWING;
SET COLOR_WIRE YELLOW;
SET COLOR_PROP MONO;
SET COLOR_DOT WHITE;
SET COLOR_ARC YELLOW;
SET COLOR_BODY GREEN;
SET COLOR_NOTE MONO;
SET PROP_DISPLAY VALUE;
SET PAGE_NUMBER P13;
FORCEADD INTEL_CORP_BPAGE..1
(0 0);
FORCEPROP 1 LAST CUSTOM_TXT_CDS <CURRENT_DESIGN_SHEET> OF <TOTAL_DESIGN_SHEETS>
J 0
(-500 25);
PAINT GREEN (-500 25);
FORCEPROP 1 LAST CUSTOM_TXT_CDS <CON_LAST_MODIFIED>
J 0
(-1925 350);
PAINT GREEN (-1925 350);
FORCEPROP 2 LAST CUSTOM_TXT_CDS <XR_PAGE_TITLE>
J 0
(-7890 5250);
DISPLAY 0.638298 (-7890 5250);
PAINT PINK (-7890 5250);
DISPLAY INVISIBLE (-7890 5250);
FORCEPROP 1 LAST SCH_REV 2.420
J 0
(-250 150);
DISPLAY 0.978723 (-250 150);
PAINT YELLOW (-250 150);
FORCEPROP 1 LAST SCH_NUMBER H4694802
J 0
(-1300 150);
DISPLAY 1.212766 (-1300 150);
PAINT YELLOW (-1300 150);
FORCEPROP 1 LAST SCH_TITLE XDP BLOCK DIAGRAM
J 0
(-7950 50);
DISPLAY 1.212766 (-7950 50);
PAINT ORANGE (-7950 50);
FORCEPROP 1 LAST SCH_ADDRESS3 Santa Clara, CA 95052-8119
J 0
(-3975 25);
DISPLAY 0.617021 (-3975 25);
PAINT GREEN (-3975 25);
FORCEPROP 1 LAST SCH_ADDRESS2 P.O. BOX 58119
J 0
(-3975 75);
DISPLAY 0.617021 (-3975 75);
PAINT GREEN (-3975 75);
FORCEPROP 1 LAST SCH_ADDRESS1 2200 Mission College Blvd.
J 0
(-3975 125);
DISPLAY 0.617021 (-3975 125);
PAINT GREEN (-3975 125);
FORCEPROP 1 LAST SCH_DEPT BESD
J 1
(-4450 100);
DISPLAY 1.212766 (-4450 100);
PAINT YELLOW (-4450 100);
FORCEPROP 1 LAST COMMENT_BODY TRUE
J 0
(12 12);
DISPLAY 0.468085 (12 12);
PAINT GREEN (12 12);
DISPLAY INVISIBLE (12 12);
FORCEPROP 2 LAST CDS_LIB mstr_symbols
J 0
(0 0);
PAINT ORANGE (0 0);
DISPLAY INVISIBLE (0 0);
FORCEPROP 2 LAST PAGE_BORDER TRUE
J 0
(-7890 5250);
DISPLAY 0.638298 (-7890 5250);
PAINT PINK (-7890 5250);
DISPLAY INVISIBLE (-7890 5250);
FORCEPROP 1 LAST CDS_CON_LAST_MODIFIED Tue Dec 01 11:47:58 2015
J 0
(-1425 325);
PAINT ORANGE (-1425 325);
DISPLAY INVISIBLE (-1425 325);
FORCEPROP 2 LAST CDS_XR_PAGE_TITLE CR-13 : @BASEBOARD_FAB2_LIB.BASEBOARD_FAB2(SCH_1):PAGE13
J 0
(-7890 5250);
DISPLAY 0.638298 (-7890 5250);
PAINT PINK (-7890 5250);
DISPLAY INVISIBLE (-7890 5250);
FORCENOTE
$CDS_IMAGE|13_XDP_JTAG_Topology.jpg|5590|4673
(-4100 2675) 0;
DISPLAY CENTER (-4100 2675);
PAINT MONO (-4100 2675);
QUIT
